FILE_TYPE = CONNECTIVITY;
{Allegro Design Entry HDL 17.2-2016 S066 (3851973) 4/6/2020}
"PAGE_NUMBER" = 527;
0"NC";
1"SG\g";
2"XP5R0V_MAC\g";
3"XP5R0V_MAC_USB\g";
4"XP3R3V_FPGA\g";
5"SG\g";
6"SG\g";
7"SG\g";
8"XP5R0V\g";
9"XP5R0V_MAC_USB\g";
10"SG\g";
11"SG\g";
12"SG\g";
13"XP5R0V_MAC_USB\g";
14"XP5R0V_MAC\g";
15"SG\g";
16"SG\g";
17"SG\g";
18"SG\g";
19"XP5R0V_MAC\g";
20"XP3R3V_FPGA\g";
21"SG\g";
22"XP5R0V_USB_CONN\g";
23"SG\g";
24"XP3R3V_FPGA\g";
25"XP3R3V_FPGA\g";
26"XP3R3V_FPGA\g";
27"SG\g";
28"SG\g";
29"ANALOG_TUNING_IN";
30"R_MAC_10MHZ_RF_OUT";
31"UART_MAC_RX_FPGA_TX";
32"UART_MAC_TX_FPGA_RX";
33"FPGA_IN_MAC_BITE OUT";
34"FPGA_IN_MAC_10MHZ_OUT";
35"R_MAC_UART_RX_FPGA_TX";
36"R_MAC_BITE OUT";
37"R_MAC_UART_TX_FPGA_RX";
38"DBG_UART_MAC_TX";
39"CONN_MICRO_USB_DM";
40"XP5R0V_USB_CONN_DET";
41"R_MAC_PPS_OUTP";
42"R_MAC_PPS_OUTN";
43"FPGA_IN_MAC_USB_OC_N";
44"MUX_USB_DM";
45"MUX_USB_DP";
46"DBG_UART_MAC_RX";
47"R_MAC_PPS_IN1P";
48"MAC_ALARM";
49"FPGA_OUT_MAC_PPS_IN0P";
50"FPGA_IN_MAC_PPS_OUTP";
51"FPGA_IN_MAC_PPS_OUTN";
52"R_MAC_PPS_IN0N";
53"FPGA_IN_MAC_ALARM_OUT_N";
54"SMA_ANALOG_TUNING_IN";
55"RSVD_DBG_USB_MUX_SEL";
56"R_MAC_PPS_IN0P";
57"FPGA_OUT_MAC_PPS_IN1P";
58"FPGA_OUT_MACUSBPOWER_EN";
59"CONN_MICRO_USB_DP";
60"UN$527$RESISTOR$I126$1";
61"XP5R0V_USB_CONN_DET";
62"USB_PWR_EN";
63"MAC_USB_DP";
64"MAC_USB_DM";
65"CONN_MICRO_USB_DP";
66"XP5R0V_USB_CONN_DET";
67"UN$527$FUSE$I244$1";
68"USB_PWR_EN";
69"UN$527$POWERMOS3PNCHV1$I232$D";
70"CONN_MICRO_USB_DM";
71"R_MAC_PPS_IN1N";
72"R_MAC_USB_DM";
73"UN$527$RESISTOR$I201$2";
74"UN$527$RESISTOR$I206$1";
75"FPGA_OUT_MAC_PPS_IN0N";
76"FPGA_OUT_MAC_PPS_IN1N";
77"MUX_USB_DM";
78"R_MAC_USB_DP";
79"MUX_USB_DP";
%"GND_SG"
"1","(-11900,-50)","0","cls","I1";
;
HDL_POWER"SG"
CDS_LIB"cls"
CDS_LMAN_SYM_OUTLINE"0,0,100,-50"
BODY_TYPE"PLUMBING";
"SGND"28;
%"GND_SG"
"1","(-4700,800)","0","cls","I100";
;
HDL_POWER"SG"
CDS_LIB"cls"
CDS_LMAN_SYM_OUTLINE"0,0,100,-50"
BODY_TYPE"PLUMBING";
"SGND"7;
%"CAPACITOR"
"2","(-4300,950)","5","passive","I103";
;
$LOCATION"C67"
CDS_LOCATION"C67"
$SEC"1"
CDS_SEC"1"
VOLTAGE"10V"
VALUE"0.1UF"
PACKAGE"0402"
NO_ASSY"TRUE"
CDS_LIB"passive"
CDS_LMAN_SYM_OUTLINE"-50,0,50,-50"
CLS_PN"G105-0B104-CK"
TOLERANCE"10%";
"2"
$PN"2"7;
"1"
$PN"1"24;
%"TS3USB3031RMGR_WQFN12"
"1","(-3300,950)","0","stdlogic","I108";
;
$LOCATION"U11"
CDS_LOCATION"U11"
$SEC"1"
CDS_SEC"1"
VALUE"TS3USB3031RMGR"
NO_ASSY"TRUE"
CLS_PN"G220-10368-01"
CDS_LIB"stdlogic"
CDS_LMAN_SYM_OUTLINE"0,0,700,-1100";
"GND"
$PN"9"1;
"MHL_N"
$PN"8"0;
"MHL_P"
$PN"7"0;
"USB2_N"
$PN"6"70;
"USB2_P"
$PN"5"59;
"USB1_N"
$PN"4"64;
"USB1_P"
$PN"3"63;
"SEL1"
$PN"2"60;
"SEL0"
$PN"1"40;
"D_N"
$PN"10"44;
"D_P"
$PN"11"45;
"VCC"
$PN"12"24;
%"RESISTOR"
"1","(-3000,1200)","0","passive","I123";
;
$LOCATION"R105"
CDS_LOCATION"R105"
$SEC"1"
CDS_SEC"1"
PACKAGE"0402"
VALUE"0OHM"
CDS_LMAN_SYM_OUTLINE"-50,50,100,-50"
CDS_LIB"passive"
CLS_PN"G155-100R0-J0"
TOLERANCE"-";
"1"
$PN"1"44;
"2"
$PN"2"64;
%"RESISTOR"
"1","(-3000,1100)","0","passive","I124";
;
$LOCATION"R106"
CDS_LOCATION"R106"
$SEC"1"
CDS_SEC"1"
PACKAGE"0402"
VALUE"0OHM"
CDS_LIB"passive"
CDS_LMAN_SYM_OUTLINE"-50,50,100,-50"
CLS_PN"G155-100R0-J0"
TOLERANCE"-";
"1"
$PN"1"45;
"2"
$PN"2"63;
%"RESISTOR"
"2","(-3500,-100)","0","passive","I126";
;
$LOCATION"R104"
CDS_LOCATION"R104"
$SEC"1"
CDS_SEC"1"
NO_ASSY"TRUE"
PACKAGE"0402"
VALUE"4.7KOHM"
CDS_LIB"passive"
CDS_LMAN_SYM_OUTLINE"-50,50,50,-100"
CLS_PN"G155-14701-01"
TOLERANCE"1%";
"1"
$PN"1"60;
"2"
$PN"2"6;
%"GND_SG"
"1","(-3550,-400)","0","cls","I128";
;
HDL_POWER"SG"
CDS_LMAN_SYM_OUTLINE"0,0,100,-50"
CDS_LIB"cls"
BODY_TYPE"PLUMBING";
"SGND"6;
%"RESISTOR"
"1","(-7100,6550)","0","passive","I13";
;
$LOCATION"R88"
CDS_LOCATION"R88"
$SEC"1"
CDS_SEC"1"
PACKAGE"0402"
VALUE"0OHM"
CDS_LIB"passive"
CDS_LMAN_SYM_OUTLINE"-50,50,100,-50"
CLS_PN"G155-100R0-J0"
TOLERANCE"-";
"1"
$PN"1"51;
"2"
$PN"2"42;
%"GND_SG"
"1","(-2400,2900)","0","cls","I139";
;
HDL_POWER"SG"
CDS_LMAN_SYM_OUTLINE"0,0,100,-50"
CDS_LIB"cls"
BODY_TYPE"PLUMBING";
"SGND"5;
%"RESISTOR"
"1","(-7100,6650)","0","passive","I14";
;
$LOCATION"R87"
CDS_LOCATION"R87"
$SEC"1"
CDS_SEC"1"
PACKAGE"0402"
VALUE"0OHM"
CDS_LIB"passive"
CDS_LMAN_SYM_OUTLINE"-50,50,100,-50"
CLS_PN"G155-100R0-J0"
TOLERANCE"-";
"1"
$PN"1"50;
"2"
$PN"2"41;
%"GND_SG"
"1","(-1150,2450)","0","cls","I143";
;
HDL_POWER"SG"
CDS_LMAN_SYM_OUTLINE"0,0,100,-50"
CDS_LIB"cls"
BODY_TYPE"PLUMBING";
"SGND"27;
%"CAPACITOR"
"2","(-1100,3000)","0","passive","I144";
;
$LOCATION"C68"
CDS_LOCATION"C68"
$SEC"1"
CDS_SEC"1"
PACKAGE"0402"
VOLTAGE"25V"
VALUE"0.1UF"
NO_ASSY"TRUE"
CLS_PN"G105-0B104-EK"
TOLERANCE"10%"
CDS_LMAN_SYM_OUTLINE"-50,0,50,-50"
CDS_LIB"passive";
"2"
$PN"2"27;
"1"
$PN"1"25;
%"CL5003148A"
"2","(-1750,3200)","0","stdlogic","I146";
;
$LOCATION"U10"
CDS_LOCATION"U10"
$SEC"2"
CDS_SEC"2"
NO_ASSY"TRUE"
PART_NUMBER"SN74LVC1G32DCKR"
CLS_PN"G220-10019-01"
CDS_LIB"stdlogic"
CDS_LMAN_SYM_OUTLINE"0,0,400,-500";
"VCC"
$PN"5"25;
"GND"
$PN"3"27;
%"CL5003148A"
"1","(-2100,4000)","0","stdlogic","I147";
;
$LOCATION"U10"
CDS_LOCATION"U10"
$SEC"1"
CDS_SEC"1"
NO_ASSY"TRUE"
CLS_PN"G220-10019-01"
CDS_LIB"stdlogic"
CDS_LMAN_SYM_OUTLINE"0,0,400,-400";
"Y"
$PN"4"62;
"B"
$PN"2"61;
"A"
$PN"1"58;
%"RESISTOR"
"2","(-2350,3400)","0","passive","I149";
;
$LOCATION"R99"
CDS_LOCATION"R99"
$SEC"1"
CDS_SEC"1"
PACKAGE"0402"
VALUE"4.7KOHM"
CLS_PN"G155-14701-01"
CDS_LIB"passive"
CDS_LMAN_SYM_OUTLINE"-50,50,50,-100"
TOLERANCE"1%";
"1"
$PN"1"58;
"2"
$PN"2"5;
%"CAPACITOR"
"1","(-8500,150)","3","passive","I15";
;
$LOCATION"C63"
CDS_LOCATION"C63"
$SEC"1"
CDS_SEC"1"
VOLTAGE"25V"
VALUE"0.1UF"
PACKAGE"0402"
NO_ASSY"TRUE"
CDS_LIB"passive"
CDS_LMAN_SYM_OUTLINE"0,50,50,-50"
TOLERANCE"10%"
CLS_PN"G105-0B104-EK";
"2"
$PN"2"17;
"1"
$PN"1"22;
%"RESISTOR"
"1","(-1950,4150)","0","passive","I155";
;
$LOCATION"R100"
CDS_LOCATION"R100"
$SEC"1"
CDS_SEC"1"
PACKAGE"0402"
VALUE"33OHM"
SIGNAL_MODEL"DEFAULT_RESISTOR_33OHM_2_1"
CDS_LMAN_SYM_OUTLINE"-50,50,100,-50"
CDS_LIB"passive"
CLS_PN"G155-133R0-01"
TOLERANCE"1%";
"1"
$PN"1"58;
"2"
$PN"2"62;
%"CAPACITOR"
"1","(-8900,150)","5","passive","I16";
;
$LOCATION"C61"
CDS_LOCATION"C61"
$SEC"1"
CDS_SEC"1"
VOLTAGE"25V"
PACKAGE"0805"
VALUE"10UF"
NO_ASSY"TRUE"
TOLERANCE"20%"
CLS_PN"G107-0F106-EM"
CDS_LMAN_SYM_OUTLINE"0,50,50,-50"
CDS_LIB"passive";
"2"
$PN"2"17;
"1"
$PN"1"22;
%"RESISTOR"
"1","(-2700,7350)","0","passive","I175";
;
$LOCATION"R98"
CDS_LOCATION"R98"
$SEC"1"
CDS_SEC"1"
PACKAGE"0402"
VALUE"0OHM"
CDS_LIB"passive"
CDS_LMAN_SYM_OUTLINE"-50,50,100,-50"
CLS_PN"G155-100R0-J0"
TOLERANCE"-";
"1"
$PN"1"72;
"2"
$PN"2"77;
%"RESISTOR"
"1","(-2700,7450)","0","passive","I176";
;
$LOCATION"R97"
CDS_LOCATION"R97"
$SEC"1"
CDS_SEC"1"
PACKAGE"0402"
VALUE"0OHM"
CLS_PN"G155-100R0-J0"
CDS_LMAN_SYM_OUTLINE"-50,50,100,-50"
CDS_LIB"passive"
TOLERANCE"-";
"1"
$PN"1"78;
"2"
$PN"2"79;
%"RESISTOR"
"1","(-8050,3800)","0","passive","I187";
;
$LOCATION"R91"
CDS_LOCATION"R91"
$SEC"1"
CDS_SEC"1"
NO_ASSY"TRUE"
PACKAGE"0402"
VALUE"33OHM"
CDS_LIB"passive"
CDS_LMAN_SYM_OUTLINE"-50,50,100,-50"
SIGNAL_MODEL"DEFAULT_RESISTOR_33OHM_2_1"
CLS_PN"G155-133R0-01"
TOLERANCE"1%";
"1"
$PN"1"29;
"2"
$PN"2"54;
%"VCC"
"1","(950,4400)","0","cls","I190";
;
VOLTAGE"3.3V"
HDL_POWER"XP3R3V_FPGA"
CDS_LIB"cls"
CDS_LMAN_SYM_OUTLINE"-250,250,250,-250"
BODY_TYPE"PLUMBING";
"$PIN0"26;
%"VCC"
"1","(-1150,3450)","0","cls","I191";
;
HDL_POWER"XP3R3V_FPGA"
VOLTAGE"3.3V"
CDS_LIB"cls"
CDS_LMAN_SYM_OUTLINE"-250,250,250,-250"
BODY_TYPE"PLUMBING";
"$PIN0"25;
%"VCC"
"1","(-4050,1150)","0","cls","I192";
;
VOLTAGE"3.3V"
HDL_POWER"XP3R3V_FPGA"
CDS_LIB"cls"
CDS_LMAN_SYM_OUTLINE"-250,250,250,-250"
BODY_TYPE"PLUMBING";
"$PIN0"24;
%"CONN_HDR_2X10_M_S_SMT"
"1","(-5150,7550)","0","connector","I193";
;
$LOCATION"P1"
CDS_LOCATION"P1"
$SEC"1"
CDS_SEC"1"
CLS_PN"G200-13077-01"
VALUE"52991-0208"
CDS_LIB"connector"
CDS_LMAN_SYM_OUTLINE"0,0,500,-1050";
"20"
$PN"20"48;
"18"
$PN"18"0;
"16"
$PN"16"0;
"14"
$PN"14"0;
"12"
$PN"12"0;
"10"
$PN"10"0;
"8"
$PN"8"21;
"6"
$PN"6"13;
"4"
$PN"4"72;
"2"
$PN"2"78;
"19"
$PN"19"42;
"17"
$PN"17"41;
"15"
$PN"15"11;
"13"
$PN"13"0;
"11"
$PN"11"0;
"9"
$PN"9"11;
"7"
$PN"7"52;
"5"
$PN"5"56;
"3"
$PN"3"71;
"1"
$PN"1"47;
%"CONN_HDR_1X3_M_S_SMT"
"1","(-5600,4000)","0","connector","I198";
;
$LOCATION"J18"
CDS_LOCATION"J18"
$SEC"1"
CDS_SEC"1"
NO_ASSY"TRUE"
CLS_PN"G205-10020-01"
CDS_LMAN_SYM_OUTLINE"0,0,300,-400"
CDS_LIB"connector";
"3"
$PN"3"23;
"2"
$PN"2"54;
"1"
$PN"1"23;
%"GND_SG"
"1","(-5100,3550)","0","cls","I199";
;
HDL_POWER"SG"
CDS_LIB"cls"
CDS_LMAN_SYM_OUTLINE"0,0,100,-50"
BODY_TYPE"PLUMBING";
"SGND"23;
%"CONN_USB_1X5_G2_GH4_F_RA_SMT"
"1","(-11200,800)","2","connector","I2";
;
$LOCATION"J11"
CDS_LOCATION"J11"
$SEC"1"
CDS_SEC"1"
VALUE"1050171001"
CLS_PN"G200-12192-01"
NO_ASSY"TRUE"
CDS_LMAN_SYM_OUTLINE"0,0,400,-800"
CDS_LIB"connector";
"GH4"
$PN"GH4"28;
"GH3"
$PN"GH3"28;
"GH2"
$PN"GH2"28;
"GH1"
$PN"GH1"28;
"G2"
$PN"G2"28;
"G1"
$PN"G1"28;
"5"
$PN"5"17;
"4"
$PN"4"0;
"3"
$PN"3"65;
"2"
$PN"2"39;
"1"
$PN"1"22;
%"RESISTOR"
"2","(-8050,500)","0","passive","I200";
;
$LOCATION"R101"
CDS_LOCATION"R101"
$SEC"1"
CDS_SEC"1"
PACKAGE"0402"
VALUE"1KOHM"
NO_ASSY"TRUE"
CDS_LIB"passive"
CDS_LMAN_SYM_OUTLINE"-50,50,50,-100"
CLS_PN"G155-11001-01"
TOLERANCE"1%";
"1"
$PN"1"22;
"2"
$PN"2"66;
%"RESISTOR"
"2","(-8050,50)","0","passive","I201";
;
$LOCATION"R102"
CDS_LOCATION"R102"
$SEC"1"
CDS_SEC"1"
PACKAGE"0402"
VALUE"1KOHM"
NO_ASSY"TRUE"
CDS_LMAN_SYM_OUTLINE"-50,50,50,-100"
CDS_LIB"passive"
CLS_PN"G155-11001-01"
TOLERANCE"1%";
"1"
$PN"1"66;
"2"
$PN"2"73;
%"RESISTOR"
"2","(-8050,-300)","0","passive","I202";
;
$LOCATION"R103"
CDS_LOCATION"R103"
$SEC"1"
CDS_SEC"1"
NO_ASSY"TRUE"
PACKAGE"0402"
VALUE"1KOHM"
CDS_LMAN_SYM_OUTLINE"-50,50,50,-100"
CDS_LIB"passive"
CLS_PN"G155-11001-01"
TOLERANCE"1%";
"1"
$PN"1"73;
"2"
$PN"2"17;
%"RESISTOR"
"1","(-4150,100)","0","passive","I204";
;
$LOCATION"R266"
CDS_LOCATION"R266"
$SEC"1"
CDS_SEC"1"
PACKAGE"0402"
VALUE"33OHM"
NO_ASSY"TRUE"
CDS_LIB"passive"
CDS_LMAN_SYM_OUTLINE"-50,50,100,-50"
SIGNAL_MODEL"DEFAULT_RESISTOR_33OHM_2_1"
CLS_PN"G155-133R0-01"
TOLERANCE"1%";
"1"
$PN"1"55;
"2"
$PN"2"40;
%"RESISTOR"
"1","(1300,3800)","0","passive","I206";
;
$LOCATION"R267"
CDS_LOCATION"R267"
$SEC"1"
CDS_SEC"1"
PACKAGE"0402"
VALUE"33OHM"
CDS_LIB"passive"
CDS_LMAN_SYM_OUTLINE"-50,50,100,-50"
SIGNAL_MODEL"DEFAULT_RESISTOR_33OHM_2_1"
CLS_PN"G155-133R0-01"
TOLERANCE"1%";
"1"
$PN"1"74;
"2"
$PN"2"43;
%"CAPACITOR"
"2","(-8800,4550)","0","passive","I208";
;
$LOCATION"C282"
CDS_LOCATION"C282"
$SEC"1"
CDS_SEC"1"
VALUE"10UF"
PACKAGE"0805"
VOLTAGE"25V"
CLS_PN"G107-0F106-EM"
CDS_LMAN_SYM_OUTLINE"-50,0,50,-50"
CDS_LIB"passive"
TOLERANCE"20%";
"2"
$PN"2"15;
"1"
$PN"1"14;
%"CAPACITOR"
"2","(-8350,4550)","0","passive","I209";
;
$LOCATION"C283"
CDS_LOCATION"C283"
$SEC"1"
CDS_SEC"1"
PACKAGE"0805"
VALUE"10UF"
VOLTAGE"25V"
TOLERANCE"20%"
CDS_LIB"passive"
CDS_LMAN_SYM_OUTLINE"-50,0,50,-50"
CLS_PN"G107-0F106-EM";
"2"
$PN"2"15;
"1"
$PN"1"14;
%"VCC"
"1","(-8100,850)","0","cls","I21";
;
VOLTAGE"5V"
HDL_POWER"XP5R0V_USB_CONN"
CDS_LIB"cls"
CDS_LMAN_SYM_OUTLINE"-250,250,250,-250"
BODY_TYPE"PLUMBING";
"$PIN0"22;
%"RESISTOR"
"1","(-1950,6700)","0","passive","I211";
;
$LOCATION"R287"
CDS_LOCATION"R287"
$SEC"1"
CDS_SEC"1"
VALUE"4.7KOHM"
PACKAGE"0402"
CLS_PN"G155-14701-01"
CDS_LIB"passive"
CDS_LMAN_SYM_OUTLINE"-50,50,100,-50"
TOLERANCE"1%";
"1"
$PN"1"53;
"2"
$PN"2"4;
%"VCC"
"1","(-1300,6850)","0","cls","I212";
;
HDL_POWER"XP3R3V_FPGA"
VOLTAGE"3.3V"
CDS_LIB"cls"
CDS_LMAN_SYM_OUTLINE"-250,250,250,-250"
BODY_TYPE"PLUMBING";
"$PIN0"4;
%"GND_SG"
"1","(-4500,6350)","0","cls","I22";
;
HDL_POWER"SG"
CDS_LIB"cls"
CDS_LMAN_SYM_OUTLINE"0,0,100,-50"
BODY_TYPE"PLUMBING";
"SGND"21;
%"NUT"
"1","(-11000,2800)","2","mech","I220";
;
$LOCATION"MAC_PIN8"
CDS_LOCATION"MAC_PIN8"
$SEC"1"
CDS_SEC"1"
PART_NUMBER"0332-0-43-80-18-27-10-0"
CLS_PN"A200-00029-FB"
CDS_LMAN_SYM_OUTLINE"-50,50,50,-50"
CDS_LIB"mech";
"1 \B"
$PN"1"35;
%"RESISTOR"
"2","(-9100,2400)","1","passive","I221";
;
$LOCATION"R265"
CDS_LOCATION"R265"
$SEC"1"
CDS_SEC"1"
VALUE"100KOHM"
PACKAGE"0402"
CLS_PN"G155-11003-01"
CDS_LMAN_SYM_OUTLINE"-50,50,50,-100"
CDS_LIB"passive"
TOLERANCE"1%";
"1"
$PN"1"20;
"2"
$PN"2"32;
%"RESISTOR"
"2","(-9100,2500)","1","passive","I222";
;
$LOCATION"R264"
CDS_LOCATION"R264"
$SEC"1"
CDS_SEC"1"
VALUE"100KOHM"
PACKAGE"0402"
CLS_PN"G155-11003-01"
CDS_LIB"passive"
CDS_LMAN_SYM_OUTLINE"-50,50,50,-100"
TOLERANCE"1%";
"1"
$PN"1"20;
"2"
$PN"2"35;
%"VCC"
"1","(-9950,2500)","0","cls","I223";
;
HDL_POWER"XP3R3V_FPGA"
VOLTAGE"3.3V"
CDS_LMAN_SYM_OUTLINE"-250,250,250,-250"
CDS_LIB"cls"
BODY_TYPE"PLUMBING";
"$PIN0"20;
%"NUT"
"1","(-11000,3050)","2","mech","I224";
;
$LOCATION"MAC_PIN7"
CDS_LOCATION"MAC_PIN7"
$SEC"1"
CDS_SEC"1"
CLS_PN"A200-00029-FB"
PART_NUMBER"0332-0-43-80-18-27-10-0"
CDS_LIB"mech"
CDS_LMAN_SYM_OUTLINE"-50,50,50,-50";
"1 \B"
$PN"1"37;
%"NUT"
"1","(-11000,3300)","2","mech","I225";
;
$LOCATION"MAC_PIN6"
CDS_LOCATION"MAC_PIN6"
$SEC"1"
CDS_SEC"1"
CLS_PN"A200-00029-FB"
PART_NUMBER"0332-0-43-80-18-27-10-0"
CDS_LIB"mech"
CDS_LMAN_SYM_OUTLINE"-50,50,50,-50";
"1 \B"
$PN"1"36;
%"NUT"
"1","(-11000,3550)","2","mech","I226";
;
$LOCATION"MAC_PIN3"
CDS_LOCATION"MAC_PIN3"
$SEC"1"
CDS_SEC"1"
CLS_PN"A200-00029-FB"
PART_NUMBER"0332-0-43-80-18-27-10-0"
CDS_LIB"mech"
CDS_LMAN_SYM_OUTLINE"-50,50,50,-50";
"1 \B"
$PN"1"30;
%"NUT"
"1","(-11000,3800)","2","mech","I227";
;
$LOCATION"MAC_PIN1"
CDS_LOCATION"MAC_PIN1"
$SEC"1"
CDS_SEC"1"
PART_NUMBER"0332-0-43-80-18-27-10-0"
CLS_PN"A200-00029-FB"
CDS_LIB"mech"
CDS_LMAN_SYM_OUTLINE"-50,50,50,-50";
"1 \B"
$PN"1"29;
%"NUT"
"1","(-11000,4150)","2","mech","I228";
;
$LOCATION"MAC_PIN4"
CDS_LOCATION"MAC_PIN4"
$SEC"1"
CDS_SEC"1"
PART_NUMBER"0332-0-43-80-18-27-10-0"
CLS_PN"A200-00029-FB"
CDS_LMAN_SYM_OUTLINE"-50,50,50,-50"
CDS_LIB"mech";
"1 \B"
$PN"1"16;
%"NUT"
"1","(-11000,4400)","2","mech","I229";
;
$LOCATION"MAC_PIN2"
CDS_LOCATION"MAC_PIN2"
$SEC"1"
CDS_SEC"1"
CLS_PN"A200-00029-FB"
PART_NUMBER"0332-0-43-80-18-27-10-0"
CDS_LIB"mech"
CDS_LMAN_SYM_OUTLINE"-50,50,50,-50";
"1 \B"
$PN"1"16;
%"RESISTOR"
"1","(-2950,6550)","0","passive","I23";
;
$LOCATION"R96"
CDS_LOCATION"R96"
$SEC"1"
CDS_SEC"1"
VALUE"33OHM"
PACKAGE"0402"
SIGNAL_MODEL"DEFAULT_RESISTOR_33OHM_2_1"
CDS_LMAN_SYM_OUTLINE"-50,50,100,-50"
CDS_LIB"passive"
CLS_PN"G155-133R0-01"
TOLERANCE"1%";
"1"
$PN"1"48;
"2"
$PN"2"53;
%"NUT"
"1","(-11000,4750)","2","mech","I230";
;
$LOCATION"MAC_PIN5"
CDS_LOCATION"MAC_PIN5"
$SEC"1"
CDS_SEC"1"
CLS_PN"A200-00029-FB"
PART_NUMBER"0332-0-43-80-18-27-10-0"
CDS_LMAN_SYM_OUTLINE"-50,50,50,-50"
CDS_LIB"mech";
"1 \B"
$PN"1"14;
%"POWERMOS_3P_PCH"
"1","(800,1450)","7","discrete","I231";
;
$LOCATION"Q3"
CDS_LOCATION"Q3"
$SEC"1"
CDS_SEC"1"
PART_NUMBER"DMP3099L-7"
CLS_PN"G121-10216-01"
NO_ASSY"TRUE"
CDS_LIB"discrete"
CDS_LMAN_SYM_OUTLINE"-200,200,200,-200";
"D"
$PN"3"67;
"S"
$PN"2"19;
"G"
$PN"1"69;
%"POWERMOS_3P_NCH_V1"
"1","(450,800)","2","discrete","I232";
;
$LOCATION"Q2"
CDS_LOCATION"Q2"
$SEC"1"
CDS_SEC"1"
PART_NUMBER"BSS138"
NO_ASSY"TRUE"
CLS_PN"G121-10200-01"
CDS_LMAN_SYM_OUTLINE"-200,200,200,-200"
CDS_LIB"discrete";
"D"
$PN"3"69;
"G"
$PN"1"68;
"S"
$PN"2"18;
%"RESISTOR"
"2","(100,1400)","0","passive","I233";
;
$LOCATION"R44"
CDS_LOCATION"R44"
$SEC"1"
CDS_SEC"1"
NO_ASSY"TRUE"
PACKAGE"0402"
VALUE"4.7KOHM"
CLS_PN"G155-14701-01"
CDS_LMAN_SYM_OUTLINE"-50,50,50,-100"
CDS_LIB"passive"
TOLERANCE"1%";
"1"
$PN"1"19;
"2"
$PN"2"69;
%"VCC"
"1","(50,2150)","0","cls","I234";
;
HDL_POWER"XP5R0V_MAC"
VOLTAGE"5"
CDS_LIB"cls"
CDS_LMAN_SYM_OUTLINE"-250,250,250,-250"
BODY_TYPE"PLUMBING";
"$PIN0"19;
%"VCC"
"1","(2100,2150)","0","cls","I235";
;
VOLTAGE"5V"
HDL_POWER"XP5R0V_MAC_USB"
CDS_LMAN_SYM_OUTLINE"-250,250,250,-250"
CDS_LIB"cls"
BODY_TYPE"PLUMBING";
"$PIN0"3;
%"GND_SG"
"1","(50,500)","0","cls","I238";
;
HDL_POWER"SG"
CDS_LMAN_SYM_OUTLINE"0,0,100,-50"
CDS_LIB"cls"
BODY_TYPE"PLUMBING";
"SGND"18;
%"RESISTOR"
"1","(-9100,2200)","0","passive","I240";
;
$LOCATION"R81"
CDS_LOCATION"R81"
$SEC"1"
CDS_SEC"1"
PACKAGE"0402"
VALUE"33OHM"
CDS_LIB"passive"
CDS_LMAN_SYM_OUTLINE"-50,50,100,-50"
SIGNAL_MODEL"DEFAULT_RESISTOR_33OHM_2_1"
CLS_PN"G155-133R0-01"
TOLERANCE"1%";
"1"
$PN"1"35;
"2"
$PN"2"46;
%"RESISTOR"
"1","(-9100,2100)","0","passive","I241";
;
$LOCATION"R82"
CDS_LOCATION"R82"
$SEC"1"
CDS_SEC"1"
PACKAGE"0402"
VALUE"33OHM"
CDS_LIB"passive"
CDS_LMAN_SYM_OUTLINE"-50,50,100,-50"
SIGNAL_MODEL"DEFAULT_RESISTOR_33OHM_2_1"
CLS_PN"G155-133R0-01"
TOLERANCE"1%";
"1"
$PN"1"37;
"2"
$PN"2"38;
%"FUSE"
"1","(1650,1850)","0","passive","I244";
;
$LOCATION"FU3"
CDS_LOCATION"FU3"
$SEC"1"
CDS_SEC"1"
NO_ASSY"TRUE"
VALUE"1A"
PART_NUMBER"0438001.WR"
CLS_PN"G280-10049-01"
CDS_LIB"passive"
CDS_LMAN_SYM_OUTLINE"-50,50,100,-50";
"2"
$PN"2"3;
"1 \B"
$PN"1"67;
%"RESISTOR"
"1","(750,1850)","0","passive","I245";
;
$LOCATION"R357"
CDS_LOCATION"R357"
$SEC"1"
CDS_SEC"1"
VALUE"0OHM"
PACKAGE"0805"
NO_ASSY"TRUE"
TOLERANCE"-"
CLS_PN"G157-100R0-J0"
CDS_LMAN_SYM_OUTLINE"-50,50,100,-50"
CDS_LIB"passive";
"1"
$PN"1"19;
"2"
$PN"2"67;
%"RESISTOR"
"1","(-7100,7150)","0","passive","I29";
;
$LOCATION"R86"
CDS_LOCATION"R86"
$SEC"1"
CDS_SEC"1"
VALUE"0OHM"
PACKAGE"0402"
CLS_PN"G155-100R0-J0"
CDS_LMAN_SYM_OUTLINE"-50,50,100,-50"
CDS_LIB"passive"
TOLERANCE"-";
"1"
$PN"1"75;
"2"
$PN"2"52;
%"GND_SG"
"1","(-11050,-650)","0","cls","I3";
;
HDL_POWER"SG"
CDS_LIB"cls"
CDS_LMAN_SYM_OUTLINE"0,0,100,-50"
BODY_TYPE"PLUMBING";
"SGND"17;
%"RESISTOR"
"1","(-7100,7250)","0","passive","I30";
;
$LOCATION"R85"
CDS_LOCATION"R85"
$SEC"1"
CDS_SEC"1"
PACKAGE"0402"
VALUE"0OHM"
CDS_LIB"passive"
CDS_LMAN_SYM_OUTLINE"-50,50,100,-50"
CLS_PN"G155-100R0-J0"
TOLERANCE"-";
"1"
$PN"1"49;
"2"
$PN"2"56;
%"RESISTOR"
"1","(-7100,7350)","0","passive","I31";
;
$LOCATION"R84"
CDS_LOCATION"R84"
$SEC"1"
CDS_SEC"1"
PACKAGE"0402"
VALUE"0OHM"
CLS_PN"G155-100R0-J0"
CDS_LMAN_SYM_OUTLINE"-50,50,100,-50"
CDS_LIB"passive"
TOLERANCE"-";
"1"
$PN"1"76;
"2"
$PN"2"71;
%"RESISTOR"
"1","(-7100,7450)","0","passive","I32";
;
$LOCATION"R83"
CDS_LOCATION"R83"
$SEC"1"
CDS_SEC"1"
PACKAGE"0402"
VALUE"0OHM"
CLS_PN"G155-100R0-J0"
CDS_LMAN_SYM_OUTLINE"-50,50,100,-50"
CDS_LIB"passive"
TOLERANCE"-";
"1"
$PN"1"57;
"2"
$PN"2"47;
%"RESISTOR"
"1","(-6050,7050)","0","passive","I33";
;
$LOCATION"R90"
CDS_LOCATION"R90"
$SEC"1"
CDS_SEC"1"
NO_ASSY"TRUE"
PACKAGE"0402"
VALUE"100OHM"
TOLERANCE"1%"
CDS_LIB"passive"
CDS_LMAN_SYM_OUTLINE"-50,50,100,-50"
CLS_PN"G155-11000-01";
"1"
$PN"1"52;
"2"
$PN"2"56;
%"RESISTOR"
"1","(-6050,7550)","0","passive","I34";
;
$LOCATION"R89"
CDS_LOCATION"R89"
$SEC"1"
CDS_SEC"1"
VALUE"100OHM"
PACKAGE"0402"
NO_ASSY"TRUE"
CLS_PN"G155-11000-01"
CDS_LIB"passive"
CDS_LMAN_SYM_OUTLINE"-50,50,100,-50"
TOLERANCE"1%";
"1"
$PN"1"47;
"2"
$PN"2"71;
%"GND_SG"
"1","(-10650,2400)","0","cls","I37";
;
HDL_POWER"SG"
CDS_LIB"cls"
CDS_LMAN_SYM_OUTLINE"0,0,100,-50"
BODY_TYPE"PLUMBING";
"SGND"16;
%"CL1001485A"
"1","(-10300,-150)","7","other","I4";
;
$LOCATION"U9"
CDS_LOCATION"U9"
$SEC"1"
CDS_SEC"1"
PART_NUMBER"SRV05-4ATCT"
CLS_PN"G122-00019-01"
NO_ASSY"TRUE"
CDS_LMAN_SYM_OUTLINE"0,0,450,-600"
CDS_LIB"other";
"6"
$PN"6"65;
"5"
$PN"5"22;
"4"
$PN"4"39;
"3"
$PN"3"0;
"2"
$PN"2"17;
"1"
$PN"1"0;
%"GND_SG"
"1","(-10250,4200)","0","cls","I45";
;
HDL_POWER"SG"
CDS_LIB"cls"
CDS_LMAN_SYM_OUTLINE"0,0,100,-50"
VOLTAGE"0"
BODY_TYPE"PLUMBING";
"SGND"15;
%"VCC"
"1","(-10450,5000)","0","cls","I46";
;
VOLTAGE"5"
HDL_POWER"XP5R0V_MAC"
CDS_LMAN_SYM_OUTLINE"-250,250,250,-250"
CDS_LIB"cls"
BODY_TYPE"PLUMBING";
"$PIN0"14;
%"CAPACITOR"
"1","(-9250,4550)","5","passive","I47";
;
$LOCATION"C58"
CDS_LOCATION"C58"
$SEC"1"
CDS_SEC"1"
VOLTAGE"25V"
VALUE"10UF"
PACKAGE"0805"
CDS_LIB"passive"
CDS_LMAN_SYM_OUTLINE"0,50,50,-50"
CLS_PN"G107-0F106-EM"
TOLERANCE"20%";
"2"
$PN"2"15;
"1"
$PN"1"14;
%"CAPACITOR"
"1","(-10200,4550)","3","passive","I48";
;
$LOCATION"C59"
CDS_LOCATION"C59"
$SEC"1"
CDS_SEC"1"
PACKAGE"0402"
VALUE"0.1UF"
VOLTAGE"25V"
CDS_LMAN_SYM_OUTLINE"0,50,50,-50"
CDS_LIB"passive"
TOLERANCE"10%"
CLS_PN"G105-0B104-EK";
"2"
$PN"2"15;
"1"
$PN"1"14;
%"VCC"
"1","(-4350,7950)","0","cls","I49";
;
VOLTAGE"5V"
HDL_POWER"XP5R0V_MAC_USB"
CDS_LIB"cls"
CDS_LMAN_SYM_OUTLINE"-250,250,250,-250"
BODY_TYPE"PLUMBING";
"$PIN0"13;
%"GND_SG"
"1","(-4250,6750)","0","cls","I50";
;
HDL_POWER"SG"
CDS_LIB"cls"
CDS_LMAN_SYM_OUTLINE"0,0,100,-50"
VOLTAGE"0"
BODY_TYPE"PLUMBING";
"SGND"12;
%"CAPACITOR"
"1","(-4200,7100)","5","passive","I51";
;
$LOCATION"C64"
CDS_LOCATION"C64"
$SEC"1"
CDS_SEC"1"
VOLTAGE"25V"
PACKAGE"0805"
VALUE"10UF"
CDS_LIB"passive"
CDS_LMAN_SYM_OUTLINE"0,50,50,-50"
CLS_PN"G107-0F106-EM"
TOLERANCE"20%";
"2"
$PN"2"12;
"1"
$PN"1"13;
%"RESISTOR"
"1","(-8050,2800)","0","passive","I52";
;
$LOCATION"R95"
CDS_LOCATION"R95"
$SEC"1"
CDS_SEC"1"
PACKAGE"0402"
VALUE"33OHM"
CDS_LIB"passive"
CDS_LMAN_SYM_OUTLINE"-50,50,100,-50"
SIGNAL_MODEL"DEFAULT_RESISTOR_33OHM_2_1"
CLS_PN"G155-133R0-01"
TOLERANCE"1%";
"1"
$PN"1"35;
"2"
$PN"2"31;
%"RESISTOR"
"1","(-8050,3300)","0","passive","I53";
;
$LOCATION"R93"
CDS_LOCATION"R93"
$SEC"1"
CDS_SEC"1"
PACKAGE"0402"
VALUE"33OHM"
SIGNAL_MODEL"DEFAULT_RESISTOR_33OHM_2_1"
CDS_LMAN_SYM_OUTLINE"-50,50,100,-50"
CDS_LIB"passive"
CLS_PN"G155-133R0-01"
TOLERANCE"1%";
"1"
$PN"1"36;
"2"
$PN"2"33;
%"RESISTOR"
"1","(-8050,3050)","0","passive","I54";
;
$LOCATION"R94"
CDS_LOCATION"R94"
$SEC"1"
CDS_SEC"1"
PACKAGE"0402"
VALUE"33OHM"
SIGNAL_MODEL"DEFAULT_RESISTOR_33OHM_2_1"
CDS_LMAN_SYM_OUTLINE"-50,50,100,-50"
CDS_LIB"passive"
CLS_PN"G155-133R0-01"
TOLERANCE"1%";
"1"
$PN"1"37;
"2"
$PN"2"32;
%"RESISTOR"
"2","(-8050,3550)","3","passive","I55";
;
$LOCATION"R92"
CDS_LOCATION"R92"
$SEC"1"
CDS_SEC"1"
PACKAGE"0402"
VALUE"100OHM"
CDS_LMAN_SYM_OUTLINE"-50,50,50,-100"
CDS_LIB"passive"
TOLERANCE"1%"
CLS_PN"G155-11000-01";
"1"
$PN"1"30;
"2"
$PN"2"34;
%"CAPACITOR"
"1","(-3700,7100)","3","passive","I56";
;
$LOCATION"C65"
CDS_LOCATION"C65"
$SEC"1"
CDS_SEC"1"
VALUE"0.1UF"
PACKAGE"0402"
VOLTAGE"25V"
CLS_PN"G105-0B104-EK"
CDS_LIB"passive"
CDS_LMAN_SYM_OUTLINE"0,50,50,-50"
TOLERANCE"10%";
"2"
$PN"2"12;
"1"
$PN"1"13;
%"CAPACITOR"
"1","(-3200,7100)","3","passive","I57";
;
$LOCATION"C66"
CDS_LOCATION"C66"
$SEC"1"
CDS_SEC"1"
VALUE"0.1UF"
VOLTAGE"25V"
PACKAGE"0402"
CLS_PN"G105-0B104-EK"
CDS_LIB"passive"
CDS_LMAN_SYM_OUTLINE"0,50,50,-50"
TOLERANCE"10%";
"2"
$PN"2"12;
"1"
$PN"1"13;
%"CAPACITOR"
"1","(-9750,4550)","3","passive","I66";
;
$LOCATION"C60"
CDS_LOCATION"C60"
$SEC"1"
CDS_SEC"1"
VOLTAGE"25V"
VALUE"0.1UF"
PACKAGE"0402"
CLS_PN"G105-0B104-EK"
TOLERANCE"10%"
CDS_LMAN_SYM_OUTLINE"0,50,50,-50"
CDS_LIB"passive";
"2"
$PN"2"15;
"1"
$PN"1"14;
%"GND_SG"
"1","(-5400,6350)","0","cls","I71";
;
HDL_POWER"SG"
CDS_LMAN_SYM_OUTLINE"0,0,100,-50"
CDS_LIB"cls"
BODY_TYPE"PLUMBING";
"SGND"11;
%"GND_SG"
"1","(-650,2850)","0","cls","I73";
;
HDL_POWER"SG"
CDS_LIB"cls"
CDS_LMAN_SYM_OUTLINE"0,0,100,-50"
BODY_TYPE"PLUMBING";
"SGND"10;
%"CAPACITOR"
"2","(-600,3400)","0","passive","I74";
;
$LOCATION"C69"
CDS_LOCATION"C69"
$SEC"1"
CDS_SEC"1"
VALUE"0.1UF"
VOLTAGE"25V"
PACKAGE"0402"
NO_ASSY"TRUE"
TOLERANCE"10%"
CDS_LMAN_SYM_OUTLINE"-50,0,50,-50"
CDS_LIB"passive"
CLS_PN"G105-0B104-EK";
"2"
$PN"2"10;
"1"
$PN"1"62;
%"CAPACITOR"
"2","(-200,3400)","0","passive","I77";
;
$LOCATION"C70"
CDS_LOCATION"C70"
$SEC"1"
CDS_SEC"1"
VOLTAGE"25V"
VALUE"0.1UF"
PACKAGE"0402"
TOLERANCE"10%"
CDS_LMAN_SYM_OUTLINE"-50,0,50,-50"
CDS_LIB"passive"
CLS_PN"G105-0B104-EK";
"2"
$PN"2"10;
"1"
$PN"1"2;
%"TPS2051BDBVT_SOT23_5"
"2","(250,3500)","0","stdlogic","I78";
;
$LOCATION"U12"
CDS_LOCATION"U12"
$SEC"2"
CDS_SEC"2"
VENDOR_PN"TPS2051BDBVT"
CLS_PN"G220-10338-01"
CDS_LMAN_SYM_OUTLINE"0,0,400,-400"
CDS_LIB"stdlogic";
"GND"
$PN"2"10;
%"TPS2051BDBVT_SOT23_5"
"1","(225,4100)","0","stdlogic","I79";
;
$LOCATION"U12"
CDS_LOCATION"U12"
$SEC"1"
CDS_SEC"1"
VENDOR_PN"TPS2051BDBVT"
CLS_PN"G220-10338-01"
CDS_LMAN_SYM_OUTLINE"0,0,500,-500"
CDS_LIB"stdlogic";
"EN"
$PN"4"62;
"IN"
$PN"5"2;
"OC* \B"
$PN"3"74;
"OUT"
$PN"1"9;
%"RESISTOR"
"2","(1350,4150)","1","passive","I83";
;
$LOCATION"R107"
CDS_LOCATION"R107"
$SEC"1"
CDS_SEC"1"
PACKAGE"0402"
VALUE"4.7KOHM"
CLS_PN"G155-14701-01"
CDS_LIB"passive"
CDS_LMAN_SYM_OUTLINE"-50,50,50,-100"
TOLERANCE"1%";
"1"
$PN"1"26;
"2"
$PN"2"43;
%"CAPACITOR"
"2","(2250,3550)","0","passive","I85";
;
$LOCATION"C71"
CDS_LOCATION"C71"
$SEC"1"
CDS_SEC"1"
VOLTAGE"25V"
VALUE"0.1UF"
PACKAGE"0402"
CLS_PN"G105-0B104-EK"
CDS_LMAN_SYM_OUTLINE"-50,0,50,-50"
CDS_LIB"passive"
TOLERANCE"10%";
"2"
$PN"2"10;
"1"
$PN"1"9;
%"VCC"
"1","(-250,4250)","0","cls","I88";
;
VOLTAGE"5"
HDL_POWER"XP5R0V_MAC"
CDS_LIB"cls"
CDS_LMAN_SYM_OUTLINE"-250,250,250,-250"
BODY_TYPE"PLUMBING";
"$PIN0"2;
%"VCC"
"1","(2200,4350)","0","cls","I89";
;
VOLTAGE"5V"
HDL_POWER"XP5R0V_MAC_USB"
CDS_LIB"cls"
CDS_LMAN_SYM_OUTLINE"-250,250,250,-250"
BODY_TYPE"PLUMBING";
"$PIN0"9;
%"FERRITEBEAD"
"1","(-8050,4800)","0","passive","I91";
;
$LOCATION"L3"
CDS_LOCATION"L3"
$SEC"1"
CDS_SEC"1"
VALUE"26OHM"
PACKAGE"0805"
CDS_LMAN_SYM_OUTLINE"0,0,200,-100"
CDS_LIB"passive"
TOLERANCE"25%"
CLS_PN"G191-10101-01";
"2"
$PN"2"8;
"1"
$PN"1"14;
%"VCC"
"1","(-7200,5000)","0","cls","I92";
;
HDL_POWER"XP5R0V"
VOLTAGE"5.0"
CDS_LIB"cls"
CDS_LMAN_SYM_OUTLINE"-250,250,250,-250"
BODY_TYPE"PLUMBING";
"$PIN0"8;
%"CAPACITOR"
"1","(-7550,4550)","3","passive","I93";
;
$LOCATION"C62"
CDS_LOCATION"C62"
$SEC"1"
CDS_SEC"1"
PACKAGE"0402"
VOLTAGE"25V"
VALUE"0.1UF"
CLS_PN"G105-0B104-EK"
TOLERANCE"10%"
CDS_LIB"passive"
CDS_LMAN_SYM_OUTLINE"0,50,50,-50";
"2"
$PN"2"15;
"1"
$PN"1"8;
%"GND_SG"
"1","(-2450,-200)","0","cls","I96";
;
HDL_POWER"SG"
VOLTAGE"0"
CDS_LMAN_SYM_OUTLINE"0,0,100,-50"
CDS_LIB"cls"
BODY_TYPE"PLUMBING";
"SGND"1;
END.
